(kicad_pcb
	(version 20260206)
	(generator "pcbnew")
	(generator_version "10.0")
	(general
		(thickness 1.6)
		(legacy_teardrops no)
	)
	(paper "A4")
	(title_block
		(title "netronome-mezz — pcbd0082-001_rev01_jul9_a.brd")
		(comment 1 "Open CloudServer (Microsoft) / footprints 195-202 of 714")
	)
	(layers
		(0 "F.Cu" signal "TOP")
		(4 "In1.Cu" signal "02_GND")
		(6 "In2.Cu" signal "03_SIG")
		(8 "In3.Cu" signal "04_SIG")
		(10 "In4.Cu" signal "05_GND")
		(12 "In5.Cu" signal "06_PWR1")
		(14 "In6.Cu" signal "07_SIG")
		(16 "In7.Cu" signal "08_SIG")
		(18 "In8.Cu" signal "09_GND")
		(2 "B.Cu" signal "BOTTOM")
		(9 "F.Adhes" user "F.Adhesive")
		(11 "B.Adhes" user "B.Adhesive")
		(13 "F.Paste" user "Package Geometry/Pastemask Top")
		(15 "B.Paste" user "Package Geometry/Pastemask Bottom")
		(5 "F.SilkS" user "Ref Des/Silkscreen Top")
		(7 "B.SilkS" user "Ref Des/Silkscreen Bottom")
		(1 "F.Mask" user "Board Geometry/Soldermask Top")
		(3 "B.Mask" user "Board Geometry/Soldermask Bottom")
		(17 "Dwgs.User" user "User.Drawings")
		(19 "Cmts.User" user "User.Comments")
		(21 "Eco1.User" user "User.Eco1")
		(23 "Eco2.User" user "User.Eco2")
		(25 "Edge.Cuts" user "Board Geometry/Outline")
		(27 "Margin" user)
		(31 "F.CrtYd" user "Package Geometry/Place Bound Top")
		(29 "B.CrtYd" user "Package Geometry/Place Bound Bottom")
		(35 "F.Fab" user "Ref Des/Assembly Top")
		(33 "B.Fab" user "Ref Des/Assembly Bottom")
		(45 "User.4" user "COMPVAL_TYPE_BOTTOM")
	)
	(footprint ""
		(layer "F.Cu")
		(at 44.196 51.816)
		(property "Reference" "R267"
			(at 0 0 0)
			(layer "F.SilkS")
			(hide yes)
			(effects
				(font
					(size 1.27 1.27)
				)
			)
		)
		(property "Value" "1.5K"
			(at -0.148158 1.3462 90)
			(unlocked yes)
			(layer "F.Fab")
			(hide yes)
			(effects
				(font
					(size 1.27 0.9652)
					(thickness 0.000001)
				)
				(justify left)
			)
		)
		(property "Device Type" "REST0055"
			(at -0.148158 1.3462 90)
			(unlocked yes)
			(layer "F.Fab")
			(hide yes)
			(effects
				(font
					(size 1.27 0.9652)
					(thickness 0.000001)
				)
				(justify left)
			)
		)
		(duplicate_pad_numbers_are_jumpers no)
		(fp_poly
			(pts
				(xy 0.635 1.0668) (xy 0.635 -1.0668) (xy -0.635 -1.0668) (xy -0.635 1.0668)
			)
			(stroke
				(width 0)
				(type default)
			)
			(fill no)
			(layer "F.CrtYd")
		)
		(fp_line
			(start -0.254 -0.508)
			(end 0.254 -0.508)
			(stroke
				(width 0.0254)
				(type default)
			)
			(layer "F.Fab")
		)
		(fp_line
			(start -0.254 0.508)
			(end -0.254 -0.508)
			(stroke
				(width 0.0254)
				(type default)
			)
			(layer "F.Fab")
		)
		(fp_line
			(start 0.254 -0.508)
			(end 0.254 0.508)
			(stroke
				(width 0.0254)
				(type default)
			)
			(layer "F.Fab")
		)
		(fp_line
			(start 0.254 0.508)
			(end -0.254 0.508)
			(stroke
				(width 0.0254)
				(type default)
			)
			(layer "F.Fab")
		)
		(pad "1" smd rect
			(at 0 -0.4191)
			(size 0.508 0.5334)
			(layers "F.Cu" "F.Mask" "F.Paste")
			(net "EXT_3.3V_THRESHOLD")
		)
		(pad "2" smd rect
			(at 0 0.4191)
			(size 0.508 0.5334)
			(layers "F.Cu" "F.Mask" "F.Paste")
			(net "EXT_3.3V")
		)
		(zone
			(layer "F.Cu")
			(hatch none 0.5)
			(connect_pads
				(clearance 0)
			)
			(min_thickness 0.25)
			(keepout
				(tracks not_allowed)
				(vias allowed)
				(pads allowed)
				(copperpour not_allowed)
				(footprints allowed)
			)
			(placement
				(enabled no)
				(sheetname "")
			)
			(fill
				(thermal_gap 0.5)
				(thermal_bridge_width 0.5)
				(island_removal_mode 0)
			)
			(polygon
				(pts
					(xy 44.2214 51.7906) (xy 44.2214 51.8414) (xy 44.1706 51.8414) (xy 44.1706 51.7906)
				)
			)
		)
	)
	(footprint ""
		(layer "F.Cu")
		(at 23.241 16.8529)
		(property "Reference" "R22"
			(at 0 0 0)
			(layer "F.SilkS")
			(hide yes)
			(effects
				(font
					(size 1.27 1.27)
				)
			)
		)
		(property "Value" "4.75K"
			(at -0.148158 1.3462 90)
			(unlocked yes)
			(layer "F.Fab")
			(hide yes)
			(effects
				(font
					(size 1.27 0.9652)
					(thickness 0.000001)
				)
				(justify left)
			)
		)
		(property "Device Type" "REST4024"
			(at -0.148158 1.3462 90)
			(unlocked yes)
			(layer "F.Fab")
			(hide yes)
			(effects
				(font
					(size 1.27 0.9652)
					(thickness 0.000001)
				)
				(justify left)
			)
		)
		(duplicate_pad_numbers_are_jumpers no)
		(fp_poly
			(pts
				(xy 0.635 1.0668) (xy 0.635 -1.0668) (xy -0.635 -1.0668) (xy -0.635 1.0668)
			)
			(stroke
				(width 0)
				(type default)
			)
			(fill no)
			(layer "F.CrtYd")
		)
		(fp_line
			(start -0.254 -0.508)
			(end 0.254 -0.508)
			(stroke
				(width 0.0254)
				(type default)
			)
			(layer "F.Fab")
		)
		(fp_line
			(start -0.254 0.508)
			(end -0.254 -0.508)
			(stroke
				(width 0.0254)
				(type default)
			)
			(layer "F.Fab")
		)
		(fp_line
			(start 0.254 -0.508)
			(end 0.254 0.508)
			(stroke
				(width 0.0254)
				(type default)
			)
			(layer "F.Fab")
		)
		(fp_line
			(start 0.254 0.508)
			(end -0.254 0.508)
			(stroke
				(width 0.0254)
				(type default)
			)
			(layer "F.Fab")
		)
		(pad "1" smd rect
			(at 0 -0.4191)
			(size 0.508 0.5334)
			(layers "F.Cu" "F.Mask" "F.Paste")
			(net "VDD_3.3V")
		)
		(pad "2" smd rect
			(at 0 0.4191)
			(size 0.508 0.5334)
			(layers "F.Cu" "F.Mask" "F.Paste")
			(net "NFP_ARM_SPI_FLASH_SCK")
		)
		(zone
			(layer "F.Cu")
			(hatch none 0.5)
			(connect_pads
				(clearance 0)
			)
			(min_thickness 0.25)
			(keepout
				(tracks not_allowed)
				(vias allowed)
				(pads allowed)
				(copperpour not_allowed)
				(footprints allowed)
			)
			(placement
				(enabled no)
				(sheetname "")
			)
			(fill
				(thermal_gap 0.5)
				(thermal_bridge_width 0.5)
				(island_removal_mode 0)
			)
			(polygon
				(pts
					(xy 23.2664 16.8275) (xy 23.2664 16.8783) (xy 23.2156 16.8783) (xy 23.2156 16.8275)
				)
			)
		)
	)
	(footprint ""
		(layer "F.Cu")
		(at 82.169 35.687 180)
		(property "Reference" "R337"
			(at 0 0 180)
			(layer "F.SilkS")
			(hide yes)
			(effects
				(font
					(size 1.27 1.27)
				)
			)
		)
		(property "Value" "0"
			(at -0.148158 1.3462 270)
			(unlocked yes)
			(layer "F.Fab")
			(hide yes)
			(effects
				(font
					(size 1.27 0.9652)
					(thickness 0.000001)
				)
				(justify left)
			)
		)
		(property "Device Type" "REST1111"
			(at -0.148158 1.3462 270)
			(unlocked yes)
			(layer "F.Fab")
			(hide yes)
			(effects
				(font
					(size 1.27 0.9652)
					(thickness 0.000001)
				)
				(justify left)
			)
		)
		(duplicate_pad_numbers_are_jumpers no)
		(fp_poly
			(pts
				(xy 0.635 1.0668) (xy 0.635 -1.0668) (xy -0.635 -1.0668) (xy -0.635 1.0668)
			)
			(stroke
				(width 0)
				(type default)
			)
			(fill no)
			(layer "F.CrtYd")
		)
		(fp_line
			(start 0.254 0.508)
			(end -0.254 0.508)
			(stroke
				(width 0.0254)
				(type default)
			)
			(layer "F.Fab")
		)
		(fp_line
			(start 0.254 -0.508)
			(end 0.254 0.508)
			(stroke
				(width 0.0254)
				(type default)
			)
			(layer "F.Fab")
		)
		(fp_line
			(start -0.254 0.508)
			(end -0.254 -0.508)
			(stroke
				(width 0.0254)
				(type default)
			)
			(layer "F.Fab")
		)
		(fp_line
			(start -0.254 -0.508)
			(end 0.254 -0.508)
			(stroke
				(width 0.0254)
				(type default)
			)
			(layer "F.Fab")
		)
		(pad "1" smd rect
			(at 0 -0.4191 180)
			(size 0.508 0.5334)
			(layers "F.Cu" "F.Mask" "F.Paste")
			(net "11N2199")
		)
		(pad "2" smd rect
			(at 0 0.4191 180)
			(size 0.508 0.5334)
			(layers "F.Cu" "F.Mask" "F.Paste")
			(net "DDR_VTT")
		)
		(zone
			(layer "F.Cu")
			(hatch none 0.5)
			(connect_pads
				(clearance 0)
			)
			(min_thickness 0.25)
			(keepout
				(tracks not_allowed)
				(vias allowed)
				(pads allowed)
				(copperpour not_allowed)
				(footprints allowed)
			)
			(placement
				(enabled no)
				(sheetname "")
			)
			(fill
				(thermal_gap 0.5)
				(thermal_bridge_width 0.5)
				(island_removal_mode 0)
			)
			(polygon
				(pts
					(xy 82.1436 35.7124) (xy 82.1436 35.6616) (xy 82.1944 35.6616) (xy 82.1944 35.7124)
				)
			)
		)
	)
	(footprint ""
		(layer "F.Cu")
		(at 79.248 26.924)
		(property "Reference" "R226"
			(at 0 0 0)
			(layer "F.SilkS")
			(hide yes)
			(effects
				(font
					(size 1.27 1.27)
				)
			)
		)
		(property "Value" "39.0"
			(at -0.148158 1.3462 90)
			(unlocked yes)
			(layer "F.Fab")
			(hide yes)
			(effects
				(font
					(size 1.27 0.9652)
					(thickness 0.000001)
				)
				(justify left)
			)
		)
		(property "Device Type" "REST0108"
			(at -0.148158 1.3462 90)
			(unlocked yes)
			(layer "F.Fab")
			(hide yes)
			(effects
				(font
					(size 1.27 0.9652)
					(thickness 0.000001)
				)
				(justify left)
			)
		)
		(duplicate_pad_numbers_are_jumpers no)
		(fp_poly
			(pts
				(xy 0.635 1.0668) (xy 0.635 -1.0668) (xy -0.635 -1.0668) (xy -0.635 1.0668)
			)
			(stroke
				(width 0)
				(type default)
			)
			(fill no)
			(layer "F.CrtYd")
		)
		(fp_line
			(start -0.254 -0.508)
			(end 0.254 -0.508)
			(stroke
				(width 0.0254)
				(type default)
			)
			(layer "F.Fab")
		)
		(fp_line
			(start -0.254 0.508)
			(end -0.254 -0.508)
			(stroke
				(width 0.0254)
				(type default)
			)
			(layer "F.Fab")
		)
		(fp_line
			(start 0.254 -0.508)
			(end 0.254 0.508)
			(stroke
				(width 0.0254)
				(type default)
			)
			(layer "F.Fab")
		)
		(fp_line
			(start 0.254 0.508)
			(end -0.254 0.508)
			(stroke
				(width 0.0254)
				(type default)
			)
			(layer "F.Fab")
		)
		(pad "1" smd rect
			(at 0 -0.4191)
			(size 0.508 0.5334)
			(layers "F.Cu" "F.Mask" "F.Paste")
			(net "DDR0_32A_CAS_L")
		)
		(pad "2" smd rect
			(at 0 0.4191)
			(size 0.508 0.5334)
			(layers "F.Cu" "F.Mask" "F.Paste")
			(net "DDR_VTT")
		)
		(zone
			(layer "F.Cu")
			(hatch none 0.5)
			(connect_pads
				(clearance 0)
			)
			(min_thickness 0.25)
			(keepout
				(tracks not_allowed)
				(vias allowed)
				(pads allowed)
				(copperpour not_allowed)
				(footprints allowed)
			)
			(placement
				(enabled no)
				(sheetname "")
			)
			(fill
				(thermal_gap 0.5)
				(thermal_bridge_width 0.5)
				(island_removal_mode 0)
			)
			(polygon
				(pts
					(xy 79.2734 26.8986) (xy 79.2734 26.9494) (xy 79.2226 26.9494) (xy 79.2226 26.8986)
				)
			)
		)
	)
	(footprint ""
		(layer "F.Cu")
		(at 24.638 35.687 180)
		(property "Reference" "R69"
			(at 0 0 180)
			(layer "F.SilkS")
			(hide yes)
			(effects
				(font
					(size 1.27 1.27)
				)
			)
		)
		(property "Value" "4.75K"
			(at -0.148158 1.3462 270)
			(unlocked yes)
			(layer "F.Fab")
			(hide yes)
			(effects
				(font
					(size 1.27 0.9652)
					(thickness 0.000001)
				)
				(justify left)
			)
		)
		(property "Device Type" "REST4024"
			(at -0.148158 1.3462 270)
			(unlocked yes)
			(layer "F.Fab")
			(hide yes)
			(effects
				(font
					(size 1.27 0.9652)
					(thickness 0.000001)
				)
				(justify left)
			)
		)
		(duplicate_pad_numbers_are_jumpers no)
		(fp_poly
			(pts
				(xy 0.635 1.0668) (xy 0.635 -1.0668) (xy -0.635 -1.0668) (xy -0.635 1.0668)
			)
			(stroke
				(width 0)
				(type default)
			)
			(fill no)
			(layer "F.CrtYd")
		)
		(fp_line
			(start 0.254 0.508)
			(end -0.254 0.508)
			(stroke
				(width 0.0254)
				(type default)
			)
			(layer "F.Fab")
		)
		(fp_line
			(start 0.254 -0.508)
			(end 0.254 0.508)
			(stroke
				(width 0.0254)
				(type default)
			)
			(layer "F.Fab")
		)
		(fp_line
			(start -0.254 0.508)
			(end -0.254 -0.508)
			(stroke
				(width 0.0254)
				(type default)
			)
			(layer "F.Fab")
		)
		(fp_line
			(start -0.254 -0.508)
			(end 0.254 -0.508)
			(stroke
				(width 0.0254)
				(type default)
			)
			(layer "F.Fab")
		)
		(pad "1" smd rect
			(at 0 -0.4191 180)
			(size 0.508 0.5334)
			(layers "F.Cu" "F.Mask" "F.Paste")
			(net "EXT_3.3V")
		)
		(pad "2" smd rect
			(at 0 0.4191 180)
			(size 0.508 0.5334)
			(layers "F.Cu" "F.Mask" "F.Paste")
			(net "DEBUG_CPLD_PGRM_JTAG_TMS")
		)
		(zone
			(layer "F.Cu")
			(hatch none 0.5)
			(connect_pads
				(clearance 0)
			)
			(min_thickness 0.25)
			(keepout
				(tracks not_allowed)
				(vias allowed)
				(pads allowed)
				(copperpour not_allowed)
				(footprints allowed)
			)
			(placement
				(enabled no)
				(sheetname "")
			)
			(fill
				(thermal_gap 0.5)
				(thermal_bridge_width 0.5)
				(island_removal_mode 0)
			)
			(polygon
				(pts
					(xy 24.6126 35.7124) (xy 24.6126 35.6616) (xy 24.6634 35.6616) (xy 24.6634 35.7124)
				)
			)
		)
	)
	(footprint ""
		(layer "F.Cu")
		(at 84.582 32.576414)
		(property "Reference" "R214"
			(at 1.04267 1.586586 90)
			(unlocked yes)
			(layer "F.SilkS")
			(effects
				(font
					(size 0.7874 0.5842)
					(thickness 0.127)
				)
				(justify left)
			)
		)
		(property "Value" "39.0"
			(at -0.148158 1.3462 90)
			(unlocked yes)
			(layer "F.Fab")
			(hide yes)
			(effects
				(font
					(size 1.27 0.9652)
					(thickness 0.000001)
				)
				(justify left)
			)
		)
		(property "Device Type" "REST0108"
			(at -0.148158 1.3462 90)
			(unlocked yes)
			(layer "F.Fab")
			(hide yes)
			(effects
				(font
					(size 1.27 0.9652)
					(thickness 0.000001)
				)
				(justify left)
			)
		)
		(duplicate_pad_numbers_are_jumpers no)
		(fp_poly
			(pts
				(xy 0.635 1.0668) (xy 0.635 -1.0668) (xy -0.635 -1.0668) (xy -0.635 1.0668)
			)
			(stroke
				(width 0)
				(type default)
			)
			(fill no)
			(layer "F.CrtYd")
		)
		(fp_line
			(start -0.254 -0.508)
			(end 0.254 -0.508)
			(stroke
				(width 0.0254)
				(type default)
			)
			(layer "F.Fab")
		)
		(fp_line
			(start -0.254 0.508)
			(end -0.254 -0.508)
			(stroke
				(width 0.0254)
				(type default)
			)
			(layer "F.Fab")
		)
		(fp_line
			(start 0.254 -0.508)
			(end 0.254 0.508)
			(stroke
				(width 0.0254)
				(type default)
			)
			(layer "F.Fab")
		)
		(fp_line
			(start 0.254 0.508)
			(end -0.254 0.508)
			(stroke
				(width 0.0254)
				(type default)
			)
			(layer "F.Fab")
		)
		(pad "1" smd rect
			(at 0 -0.4191)
			(size 0.508 0.5334)
			(layers "F.Cu" "F.Mask" "F.Paste")
			(net "DDR0_32A_A8")
		)
		(pad "2" smd rect
			(at 0 0.4191)
			(size 0.508 0.5334)
			(layers "F.Cu" "F.Mask" "F.Paste")
			(net "DDR_VTT")
		)
		(zone
			(layer "F.Cu")
			(hatch none 0.5)
			(connect_pads
				(clearance 0)
			)
			(min_thickness 0.25)
			(keepout
				(tracks not_allowed)
				(vias allowed)
				(pads allowed)
				(copperpour not_allowed)
				(footprints allowed)
			)
			(placement
				(enabled no)
				(sheetname "")
			)
			(fill
				(thermal_gap 0.5)
				(thermal_bridge_width 0.5)
				(island_removal_mode 0)
			)
			(polygon
				(pts
					(xy 84.6074 32.551014) (xy 84.6074 32.601814) (xy 84.5566 32.601814) (xy 84.5566 32.551014)
				)
			)
		)
	)
	(footprint ""
		(layer "F.Cu")
		(at 0.254 36.83)
		(property "Reference" "TP14"
			(at -2.00533 1.016 90)
			(unlocked yes)
			(layer "F.SilkS")
			(effects
				(font
					(size 0.7874 0.5842)
					(thickness 0.127)
				)
				(justify left)
			)
		)
		(property "Value" "*"
			(at -0.4826 -0.14732 0)
			(unlocked yes)
			(layer "F.Fab")
			(hide yes)
			(effects
				(font
					(size 1.27 0.9652)
					(thickness 0.000001)
				)
				(justify left)
			)
		)
		(property "Device Type" "TP_SMALL"
			(at -0.4826 -0.14732 0)
			(unlocked yes)
			(layer "F.Fab")
			(hide yes)
			(effects
				(font
					(size 1.27 0.9652)
					(thickness 0.000001)
				)
				(justify left)
			)
		)
		(duplicate_pad_numbers_are_jumpers no)
		(fp_line
			(start -0.8636 -0.8636)
			(end -0.8636 0.8636)
			(stroke
				(width 0.1524)
				(type default)
			)
			(layer "F.SilkS")
		)
		(fp_line
			(start -0.8636 0.8636)
			(end 0.8636 0.8636)
			(stroke
				(width 0.1524)
				(type default)
			)
			(layer "F.SilkS")
		)
		(fp_line
			(start 0.8636 -0.8636)
			(end -0.8636 -0.8636)
			(stroke
				(width 0.1524)
				(type default)
			)
			(layer "F.SilkS")
		)
		(fp_line
			(start 0.8636 0.8636)
			(end 0.8636 -0.8636)
			(stroke
				(width 0.1524)
				(type default)
			)
			(layer "F.SilkS")
		)
		(fp_poly
			(pts
				(xy -0.635 -0.635) (xy -0.635 0.635) (xy 0.635 0.635) (xy 0.635 -0.635)
			)
			(stroke
				(width 0)
				(type default)
			)
			(fill no)
			(layer "F.CrtYd")
		)
		(pad "1" smd rect
			(at 0 0)
			(size 1.27 1.27)
			(layers "F.Cu" "F.Mask" "F.Paste")
			(net "PWR_GOOD_LED_L")
		)
	)
	(footprint ""
		(layer "F.Cu")
		(at 23.2537 41.021 90)
		(property "Reference" "C144"
			(at -3.83667 0.4953 0)
			(unlocked yes)
			(layer "F.SilkS")
			(effects
				(font
					(size 0.7874 0.5842)
					(thickness 0.127)
				)
				(justify left)
			)
		)
		(property "Value" ""
			(at 0 0 90)
			(layer "F.Fab")
			(effects
				(font
					(size 1.27 1.27)
				)
			)
		)
		(duplicate_pad_numbers_are_jumpers no)
		(fp_arc
			(start 0 -0.508)
			(mid 0.209 -0.463015)
			(end 0.381 -0.336042)
			(stroke
				(width 0.2032)
				(type default)
			)
			(layer "F.SilkS")
		)
		(fp_arc
			(start -0.381 -0.335991)
			(mid -0.209012 -0.462996)
			(end 0 -0.508)
			(stroke
				(width 0.2032)
				(type default)
			)
			(layer "F.SilkS")
		)
		(fp_arc
			(start 0.381 0.336017)
			(mid 0.20901 0.463015)
			(end 0 0.508)
			(stroke
				(width 0.2032)
				(type default)
			)
			(layer "F.SilkS")
		)
		(fp_arc
			(start 0 0.508)
			(mid -0.209017 0.463007)
			(end -0.381 0.335991)
			(stroke
				(width 0.2032)
				(type default)
			)
			(layer "F.SilkS")
		)
		(fp_circle
			(center 0 0)
			(end 0 0.508)
			(stroke
				(width 0.2032)
				(type default)
			)
			(fill no)
			(layer "F.SilkS")
		)
		(fp_poly
			(pts
				(xy -2.286 1.778) (xy -2.286 -1.778) (xy 2.286 -1.778) (xy 2.286 1.778)
			)
			(stroke
				(width 0)
				(type default)
			)
			(fill no)
			(layer "F.CrtYd")
		)
		(fp_line
			(start 1.524 -1.27)
			(end 1.524 1.27)
			(stroke
				(width 0.0254)
				(type default)
			)
			(layer "F.Fab")
		)
		(fp_line
			(start -1.524 -1.27)
			(end 1.524 -1.27)
			(stroke
				(width 0.0254)
				(type default)
			)
			(layer "F.Fab")
		)
		(fp_line
			(start 1.524 1.27)
			(end -1.524 1.27)
			(stroke
				(width 0.0254)
				(type default)
			)
			(layer "F.Fab")
		)
		(fp_line
			(start -1.524 1.27)
			(end -1.524 -1.27)
			(stroke
				(width 0.0254)
				(type default)
			)
			(layer "F.Fab")
		)
		(pad "1" smd rect
			(at -1.4224 0 180)
			(size 2.7432 1.3716)
			(layers "F.Cu" "F.Mask" "F.Paste")
			(net "10N2407")
		)
		(pad "2" smd rect
			(at 1.4224 0 180)
			(size 2.7432 1.3716)
			(layers "F.Cu" "F.Mask" "F.Paste")
			(net "GND")
		)
	)
)
